# T6G (Grand Teton) — schematic parts with pin connectivity, parts 3179–3330 of 8303; source: Cadence DE-HDL packaged netlist (pstxprt.dat, pstxnet.dat, pstchip.dat)

PC397_2  Q_CAP  22UF 4V 20% X6S  pkg C0805  page 218 : 1 = PVDDCR_CPU1_P1 ; 2 = GND
PC398_1  Q_CAP  22UF 4V 20% X6S  pkg C0805  page 218 : 1 = PVDDCR_CPU1_P1 ; 2 = GND
PC399  Q_CAP  2.2UF 10V 10% X6S  pkg C0402  page 219 : 1 = PVDDCR_CPU1_P1_VCC4 ; 2 = GND
PC400  Q_CAP  2.2UF 10V 10% X6S  pkg C0402  page 219 : 1 = PVDDCR_CPU1_P1_VCC3 ; 2 = GND
PC401_C1P1_4  Q_CAP  2.2UF 10V 10% X6S  pkg C0402  page 219 : 1 = PVDDCR_CPU1_P1_PVCC ; 2 = GND
PC402_C1P1_3  Q_CAP  2.2UF 10V 10% X6S  pkg C0402  page 219 : 1 = PVDDCR_CPU1_P1_PVCC ; 2 = GND
PC403_4  Q_CAP  0.1UF 25V 10% X7R  pkg 0402  page 219 : 1 = PVDDCR_CPU1_P1_VCCS ; 2 = GND
PC404_3  Q_CAP  0.1UF 25V 10% X7R  pkg 0402  page 219 : 1 = PVDDCR_CPU1_P1_VCCS ; 2 = GND
PC405_4  Q_CAP  0.1UF 25V 10% X7R  pkg 0402  page 219 : 1 = SW_P12V_AUX_PVDDCR_CPU1_P1_FLT ; 2 = GND
PC406_3  Q_CAP  1UF 25V 10% X6S  pkg C0402  page 219 : 1 = SW_P12V_AUX_PVDDCR_CPU1_P1_FLT ; 2 = GND
PC407_4  Q_CAP  1UF 25V 10% X6S  pkg C0402  page 219 : 1 = SW_P12V_AUX_PVDDCR_CPU1_P1_FLT ; 2 = GND
PC408_3  Q_CAP  0.1UF 25V 10% X7R  pkg 0402  page 219 : 1 = SW_P12V_AUX_PVDDCR_CPU1_P1_FLT ; 2 = GND
PC409_4  Q_CAP  22UF 16V 20% X6S  pkg C0805  page 219 : 1 = SW_P12V_AUX_PVDDCR_CPU1_P1_FLT ; 2 = GND
PC410_3  Q_CAP  22UF 16V 20% X6S  pkg C0805  page 219 : 1 = SW_P12V_AUX_PVDDCR_CPU1_P1_FLT ; 2 = GND
PC411_4  Q_CAP  22UF 16V 20% X6S  pkg C0805  page 219 : 1 = SW_P12V_AUX_PVDDCR_CPU1_P1_FLT ; 2 = GND
PC412_3  Q_CAP  22UF 16V 20% X6S  pkg C0805  page 219 : 1 = SW_P12V_AUX_PVDDCR_CPU1_P1_FLT ; 2 = GND
PC413  Q_CAP  0.22UF 16V 10% X7R  pkg 0402  page 219 : 1 = SW_PVDDCR_CPU1_P1_BOOT4_R ; 2 = SW_PVDDCR_CPU1_P1_BOOTR4
PC414  Q_CAP  0.22UF 16V 10% X7R  pkg 0402  page 219 : 1 = SW_PVDDCR_CPU1_P1_BOOT3_R ; 2 = SW_PVDDCR_CPU1_P1_BOOTR3
PC415_4  Q_CAP  22UF 16V 20% X6S  pkg C0805  page 219 : 1 = SW_P12V_AUX_PVDDCR_CPU1_P1_FLT ; 2 = GND
PC416_3  Q_CAP  22UF 16V 20% X6S  pkg C0805  page 219 : 1 = SW_P12V_AUX_PVDDCR_CPU1_P1_FLT ; 2 = GND
PC417_3  Q_CAP  22UF 4V 20% X6S  pkg C0805  page 219 : 1 = PVDDCR_CPU1_P1 ; 2 = GND
PC418_4  Q_CAP  22UF 4V 20% X6S  pkg C0805  page 219 : 1 = PVDDCR_CPU1_P1 ; 2 = GND
PC419_3  Q_CAP  22UF 4V 20% X6S  pkg C0805  page 219 : 1 = PVDDCR_CPU1_P1 ; 2 = GND
PC420_4  Q_CAP  22UF 4V 20% X6S  pkg C0805  page 219 : 1 = PVDDCR_CPU1_P1 ; 2 = GND
PC421  Q_CAP  2.2UF 10V 10% X6S  pkg C0402  page 220 : 1 = PVDDCR_CPU1_P1_VCC5 ; 2 = GND
PC422_5  Q_CAP  0.1UF 25V 10% X7R  pkg 0402  page 220 : 1 = PVDDCR_CPU1_P1_VCCS ; 2 = GND
PC423_C1P1_5  Q_CAP  2.2UF 10V 10% X6S  pkg C0402  page 220 : 1 = PVDDCR_CPU1_P1_PVCC ; 2 = GND
PC424_5  Q_CAP  1UF 25V 10% X6S  pkg C0402  page 220 : 1 = SW_P12V_AUX_PVDDCR_CPU1_P1_FLT ; 2 = GND
PC425_5  Q_CAP  0.1UF 25V 10% X7R  pkg 0402  page 220 : 1 = SW_P12V_AUX_PVDDCR_CPU1_P1_FLT ; 2 = GND
PC426_5  Q_CAP  22UF 16V 20% X6S  pkg C0805  page 220 : 1 = SW_P12V_AUX_PVDDCR_CPU1_P1_FLT ; 2 = GND
PC427_5  Q_CAP  22UF 16V 20% X6S  pkg C0805  page 220 : 1 = SW_P12V_AUX_PVDDCR_CPU1_P1_FLT ; 2 = GND
PC428  Q_CAP  0.22UF 16V 10% X7R  pkg 0402  page 220 : 1 = SW_PVDDCR_CPU1_P1_BOOT5_R ; 2 = SW_PVDDCR_CPU1_P1_BOOTR5
PC429_5  Q_CAP  22UF 16V 20% X6S  pkg C0805  page 220 : 1 = SW_P12V_AUX_PVDDCR_CPU1_P1_FLT ; 2 = GND
PC430_5  Q_CAP  22UF 4V 20% X6S  pkg C0805  page 220 : 1 = PVDDCR_CPU1_P1 ; 2 = GND
PC431_5  Q_CAP  22UF 4V 20% X6S  pkg C0805  page 220 : 1 = PVDDCR_CPU1_P1 ; 2 = GND
PC432  Q_CAP  2.2UF 10V 10% X6S  pkg C0402  page 222 : 1 = PVDDIO_P1_VCC2 ; 2 = GND
PC433  Q_CAP  2.2UF 10V 10% X6S  pkg C0402  page 222 : 1 = PVDDIO_P1_VCC1 ; 2 = GND
PC434_IOP1_2  Q_CAP  2.2UF 10V 10% X6S  pkg C0402  page 222 : 1 = PVDDCR_CPU1_P1_PVCC ; 2 = GND
PC435_7  Q_CAP  0.1UF 25V 10% X7R  pkg 0402  page 222 : 1 = PVDDCR_CPU1_P1_VCCS ; 2 = GND
PC436_8  Q_CAP  0.1UF 25V 10% X7R  pkg 0402  page 222 : 1 = PVDDCR_CPU1_P1_VCCS ; 2 = GND
PC437_IOP1_1  Q_CAP  2.2UF 10V 10% X6S  pkg C0402  page 222 : 1 = PVDDCR_CPU1_P1_PVCC ; 2 = GND
PC438  Q_CAP  0.1UF 25V 10% X7R  pkg 0402  page 222 : 1 = P12V_AUX ; 2 = GND
PC438_1  Q_CAP  0.1UF 25V 10% X7R  pkg 0402  page 222 : 1 = SW_P12V_AUX_PVDDIO_P1_FLT ; 2 = GND
PC439_2  Q_CAP  0.1UF 25V 10% X7R  pkg 0402  page 222 : 1 = SW_P12V_AUX_PVDDIO_P1_FLT ; 2 = GND
PC440_1  Q_CAP  1UF 25V 10% X6S  pkg C0402  page 222 : 1 = SW_P12V_AUX_PVDDIO_P1_FLT ; 2 = GND
PC441_2  Q_CAP  1UF 25V 10% X6S  pkg C0402  page 222 : 1 = SW_P12V_AUX_PVDDIO_P1_FLT ; 2 = GND
PC442_1  Q_CAP  22UF 16V 20% X6S  pkg C0805  page 222 : 1 = SW_P12V_AUX_PVDDIO_P1_FLT ; 2 = GND
PC443_2  Q_CAP  22UF 16V 20% X6S  pkg C0805  page 222 : 1 = SW_P12V_AUX_PVDDIO_P1_FLT ; 2 = GND
PC444_1  Q_CAP  22UF 16V 20% X6S  pkg C0805  page 222 : 1 = SW_P12V_AUX_PVDDIO_P1_FLT ; 2 = GND
PC445  Q_CAP  0.22UF 16V 10% X7R  pkg 0402  page 222 : 1 = SW_PVDDIO_P1_BOOT2_R ; 2 = SW_PVDDIO_P1_BOOTR2
PC446_2  Q_CAP  22UF 16V 20% X6S  pkg C0805  page 222 : 1 = SW_P12V_AUX_PVDDIO_P1_FLT ; 2 = GND
PC447  Q_CAP  0.22UF 16V 10% X7R  pkg 0402  page 222 : 1 = SW_PVDDIO_P1_BOOT1_R ; 2 = SW_PVDDIO_P1_BOOTR1
PC448_1  Q_CAP  22UF 16V 20% X6S  pkg C0805  page 222 : 1 = SW_P12V_AUX_PVDDIO_P1_FLT ; 2 = GND
PC449_2  Q_CAP  22UF 16V 20% X6S  pkg C0805  page 222 : 1 = SW_P12V_AUX_PVDDIO_P1_FLT ; 2 = GND
PC450  Q_CAPP  470UF 2.5V 20% SPCAP  pkg SMLF  page 222 : 1 = PVDDIO_P1 ; 2 = GND
PC451  Q_CAP  100NF 50V 10% X7R  pkg C0402  page 222 : 1 = PVDDIO_P1 ; 2 = GND
PC452  Q_CAPP  470UF 2.5V 20% SPCAP  pkg SMLF  page 222 : 1 = PVDDIO_P1 ; 2 = GND
PC454  Q_CAPP  270UF 16V 20% OSCON  pkg SMLF  page 222 : 1 = SW_P12V_AUX_PVDDIO_P1_FLT ; 2 = GND
PC455  Q_CAPP  470UF 2.5V 20% EMPTY  pkg SMLF  page 222 : 1 = PVDDIO_P1 ; 2 = GND
PC456_1  Q_CAP  22UF 4V 20% X6S  pkg C0805  page 222 : 1 = PVDDIO_P1 ; 2 = GND
PC458_2  Q_CAP  22UF 4V 20% X6S  pkg C0805  page 222 : 1 = PVDDIO_P1 ; 2 = GND
PC459_1  Q_CAP  22UF 4V 20% X6S  pkg C0805  page 222 : 1 = PVDDIO_P1 ; 2 = GND
PC460_2  Q_CAP  22UF 4V 20% X6S  pkg C0805  page 222 : 1 = PVDDIO_P1 ; 2 = GND
PC462  Q_CAP  0.1UF 25V 10% X7R  pkg 0402  page 193 : 1 = PVDDCR_CPU0_P0_VMON ; 2 = GND
PC463  Q_CAP  3300PF 50V 10% X7R  pkg 0402  page 193 : 1 = VSENSE_PVDDCR_CPU0_P0_VSEN0 ; 2 = VSENSE_VSS_SENSE_A_P0
PC464  Q_CAP  3300PF 50V 10% X7R  pkg 0402  page 193 : 1 = VSENSE_PVDDCR_SOC_P0_VSEN1 ; 2 = VSENSE_VSS_SENSE_A_P0
PC466  Q_CAP  1UF 6.3V 10% X7R  pkg 0402  page 193 : 1 = PVDD18_S5_P0 ; 2 = GND
PC469  Q_CAP  470PF 50V 10% X7R  pkg 0402  page 193 : 1 = PVDDCR_CPU0_P0_TEMP0 ; 2 = GND
PC470  Q_CAP  10UF 6.3V 20% X6S  pkg C0402  page 193 : 1 = PVDDCR_CPU0_P0_VCCS ; 2 = GND
PC471  Q_CAP  1UF 16V 10% X6S  pkg C0402  page 193 : 1 = PVDDCR_CPU0_P0_VCC ; 2 = GND
PC472  Q_CAP  470PF 50V 10% X7R  pkg 0402  page 193 : 1 = PVDDCR_SOC_P0_TEMP1 ; 2 = GND
PC473  Q_CAPP  100UF 16V 20% OSCON  pkg SMLF  page 365 : 1 = SW_P12V_AUX_P0V9_RETIMER_CPU1_FLT ; 2 = GND
PC473_1  Q_CAP  0.1UF 25V 10% X7R  pkg 0402  page 194 : 1 = PVDDCR_CPU0_P0_VCCS ; 2 = GND
PC474_2  Q_CAP  0.1UF 25V 10% X7R  pkg 0402  page 194 : 1 = PVDDCR_CPU0_P0_VCCS ; 2 = GND
PC475  Q_CAP  2.2UF 10V 10% X6S  pkg C0402  page 194 : 1 = PVDDCR_CPU0_P0_VCC1 ; 2 = GND
PC476  Q_CAP  2.2UF 10V 10% X6S  pkg C0402  page 194 : 1 = PVDDCR_CPU0_P0_VCC2 ; 2 = GND
PC477_C0P0_1  Q_CAP  2.2UF 10V 10% X6S  pkg C0402  page 194 : 1 = PVDDCR_CPU0_P0_PVCC ; 2 = GND
PC478_C0P0_2  Q_CAP  2.2UF 10V 10% X6S  pkg C0402  page 194 : 1 = PVDDCR_CPU0_P0_PVCC ; 2 = GND
PC479  Q_CAP  0.1UF 25V 10% X7R  pkg 0402  page 194 : 1 = P12V_AUX ; 2 = GND
PC479_1  Q_CAP  0.1UF 25V 10% X7R  pkg 0402  page 194 : 1 = SW_P12V_AUX_PVDDCR_CPU0_P0_FLT ; 2 = GND
PC480_2  Q_CAP  1UF 25V 10% X6S  pkg C0402  page 194 : 1 = SW_P12V_AUX_PVDDCR_CPU0_P0_FLT ; 2 = GND
PC481_1  Q_CAP  1UF 25V 10% X6S  pkg C0402  page 194 : 1 = SW_P12V_AUX_PVDDCR_CPU0_P0_FLT ; 2 = GND
PC482_2  Q_CAP  0.1UF 25V 10% X7R  pkg 0402  page 194 : 1 = SW_P12V_AUX_PVDDCR_CPU0_P0_FLT ; 2 = GND
PC483_1  Q_CAP  22UF 16V 20% X6S  pkg C0805  page 194 : 1 = SW_P12V_AUX_PVDDCR_CPU0_P0_FLT ; 2 = GND
PC484_2  Q_CAP  22UF 16V 20% X6S  pkg C0805  page 194 : 1 = SW_P12V_AUX_PVDDCR_CPU0_P0_FLT ; 2 = GND
PC485_1  Q_CAP  22UF 16V 20% X6S  pkg C0805  page 194 : 1 = SW_P12V_AUX_PVDDCR_CPU0_P0_FLT ; 2 = GND
PC486_2  Q_CAP  22UF 16V 20% X6S  pkg C0805  page 194 : 1 = SW_P12V_AUX_PVDDCR_CPU0_P0_FLT ; 2 = GND
PC487_1  Q_CAP  22UF 16V 20% X6S  pkg C0805  page 194 : 1 = SW_P12V_AUX_PVDDCR_CPU0_P0_FLT ; 2 = GND
PC488_2  Q_CAP  22UF 16V 20% X6S  pkg C0805  page 194 : 1 = SW_P12V_AUX_PVDDCR_CPU0_P0_FLT ; 2 = GND
PC489  Q_CAP  0.22UF 16V 10% X7R  pkg 0402  page 194 : 1 = SW_PVDDCR_CPU0_P0_BOOT1_RC ; 2 = SW_PVDDCR_CPU0_P0_PH1
PC490  Q_CAP  0.22UF 16V 10% X7R  pkg 0402  page 194 : 1 = SW_PVDDCR_CPU0_P0_BOOT2_RC ; 2 = SW_PVDDCR_CPU0_P0_PH2
PC491  Q_CAPP  270UF 16V 20% OSCON  pkg THLF  page 194 : 1 = SW_P12V_AUX_PVDDCR_CPU0_P0_FLT ; 2 = GND
PC492  Q_CAPP  270UF 16V 20% OSCON  pkg THLF  page 194 : 1 = SW_P12V_AUX_PVDDCR_CPU0_P0_FLT ; 2 = GND
PC494  Q_CAPP  220UF 4V 20% SPCAP  pkg SMLF  page 194 : 1 = PVDDCR_CPU0_P0 ; 2 = GND
PC495  Q_CAPP  220UF 4V 20% SPCAP  pkg SMLF  page 194 : 1 = PVDDCR_CPU0_P0 ; 2 = GND
PC496  Q_CAPP  220UF 4V 20% SPCAP  pkg SMLF  page 194 : 1 = PVDDCR_CPU0_P0 ; 2 = GND
PC497  Q_CAP  0.1UF 25V 10% X7R  pkg 0402  page 194 : 1 = PVDDCR_CPU0_P0 ; 2 = GND
PC498  Q_CAPP  220UF 4V 20% SPCAP  pkg SMLF  page 194 : 1 = PVDDCR_CPU0_P0 ; 2 = GND
PC499_2  Q_CAP  22UF 4V 20% X6S  pkg C0805  page 194 : 1 = PVDDCR_CPU0_P0 ; 2 = GND
PC500_1  Q_CAP  22UF 4V 20% X6S  pkg C0805  page 194 : 1 = PVDDCR_CPU0_P0 ; 2 = GND
PC501_2  Q_CAP  22UF 4V 20% X6S  pkg C0805  page 194 : 1 = PVDDCR_CPU0_P0 ; 2 = GND
PC502_1  Q_CAP  22UF 4V 20% X6S  pkg C0805  page 194 : 1 = PVDDCR_CPU0_P0 ; 2 = GND
PC503_1  Q_CAP  0.1UF 25V 10% X7R  pkg 0402  page 225 : 1 = PVDD11_S3_P1_VCCS ; 2 = GND
PC504_2  Q_CAP  0.1UF 25V 10% X7R  pkg 0402  page 225 : 1 = PVDD11_S3_P1_VCCS ; 2 = GND
PC505  Q_CAP  2.2UF 10V 10% X6S  pkg C0402  page 225 : 1 = PVDD11_S3_P1_VCC1 ; 2 = GND
PC506  Q_CAP  2.2UF 10V 10% X6S  pkg C0402  page 225 : 1 = PVDD11_S3_P1_VCC2 ; 2 = GND
PC507_11P1_1  Q_CAP  2.2UF 10V 10% X6S  pkg C0402  page 225 : 1 = PVDD11_S3_P1_PVCC ; 2 = GND
PC508_11P1_2  Q_CAP  2.2UF 10V 10% X6S  pkg C0402  page 225 : 1 = PVDD11_S3_P1_PVCC ; 2 = GND
PC509_1  Q_CAP  0.1UF 25V 10% X7R  pkg 0402  page 225 : 1 = SW_P12V_AUX_PVDD11_S3_P1_FLT ; 2 = GND
PC510_2  Q_CAP  0.1UF 25V 10% X7R  pkg 0402  page 225 : 1 = SW_P12V_AUX_PVDD11_S3_P1_FLT ; 2 = GND
PC511  Q_CAP  0.1UF 25V 10% X7R  pkg 0402  page 225 : 1 = P12V_AUX ; 2 = GND
PC511_1  Q_CAP  1UF 25V 10% X6S  pkg C0402  page 225 : 1 = SW_P12V_AUX_PVDD11_S3_P1_FLT ; 2 = GND
PC512_2  Q_CAP  1UF 25V 10% X6S  pkg C0402  page 225 : 1 = SW_P12V_AUX_PVDD11_S3_P1_FLT ; 2 = GND
PC513_1  Q_CAP  22UF 16V 20% X6S  pkg C0805  page 225 : 1 = SW_P12V_AUX_PVDD11_S3_P1_FLT ; 2 = GND
PC514  Q_CAP  0.1UF 25V 10% EMPTY  pkg 0402  page 364 : 1 = P0V9_RETIMER_CPU1_VMON ; 2 = GND
PC514_2  Q_CAP  22UF 16V 20% X6S  pkg C0805  page 225 : 1 = SW_P12V_AUX_PVDD11_S3_P1_FLT ; 2 = GND
PC515_1  Q_CAP  22UF 16V 20% X6S  pkg C0805  page 225 : 1 = SW_P12V_AUX_PVDD11_S3_P1_FLT ; 2 = GND
PC516_2  Q_CAP  22UF 16V 20% X6S  pkg C0805  page 225 : 1 = SW_P12V_AUX_PVDD11_S3_P1_FLT ; 2 = GND
PC517_1  Q_CAP  22UF 16V 20% X6S  pkg C0805  page 225 : 1 = SW_P12V_AUX_PVDD11_S3_P1_FLT ; 2 = GND
PC518_2  Q_CAP  22UF 16V 20% X6S  pkg C0805  page 225 : 1 = SW_P12V_AUX_PVDD11_S3_P1_FLT ; 2 = GND
PC519  Q_CAP  0.22UF 16V 10% X7R  pkg 0402  page 225 : 1 = SW_PVDD11_S3_P1_BOOT1_RC ; 2 = SW_PVDD11_S3_P1_PH1
PC520  Q_CAP  0.22UF 16V 10% X7R  pkg 0402  page 225 : 1 = SW_PVDD11_S3_P1_BOOT2_RC ; 2 = SW_PVDD11_S3_P1_PH2
PC521_1  Q_CAP  22UF 16V 20% X6S  pkg C0805  page 225 : 1 = SW_P12V_AUX_PVDD11_S3_P1_FLT ; 2 = GND
PC522  Q_CAPP  270UF 16V 20% OSCON  pkg THLF  page 225 : 1 = SW_P12V_AUX_PVDD11_S3_P1_FLT ; 2 = GND
PC523  Q_CAP  470PF 50V 10% X7R  pkg 0402  page 364 : 1 = P0V9_RETIMER_CPU1_TEMP0 ; 2 = GND
PC523_2  Q_CAP  22UF 4V 20% X6S  pkg C0805  page 225 : 1 = PVDD11_S3_P1 ; 2 = GND
PC524  Q_CAP  100NF 50V 10% X7R  pkg C0402  page 225 : 1 = PVDD11_S3_P1 ; 2 = GND
PC525  Q_CAPP  470UF 2.5V 20% SPCAP  pkg SMLF  page 225 : 1 = PVDD11_S3_P1 ; 2 = GND
PC526_1  Q_CAP  22UF 4V 20% X6S  pkg C0805  page 225 : 1 = PVDD11_S3_P1 ; 2 = GND
PC527_2  Q_CAP  22UF 4V 20% X6S  pkg C0805  page 225 : 1 = PVDD11_S3_P1 ; 2 = GND
PC528  Q_CAPP  470UF 2.5V 20% SPCAP  pkg SMLF  page 225 : 1 = PVDD11_S3_P1 ; 2 = GND
PC529_1  Q_CAP  22UF 4V 20% X6S  pkg C0805  page 225 : 1 = PVDD11_S3_P1 ; 2 = GND
PC530  Q_CAPP  390UF 2.5V 20% ALUM  pkg SMLF  page 225 : 1 = PVDD11_S3_P1 ; 2 = GND
PC531  Q_CAPP  390UF 2.5V 20% ALUM  pkg SMLF  page 225 : 1 = PVDD11_S3_P1 ; 2 = GND
PC532  Q_CAPP  390UF 2.5V 20% ALUM  pkg SMLF  page 225 : 1 = PVDD11_S3_P1 ; 2 = GND
PC534  Q_CAPP  470UF 2.5V 20% SPCAP  pkg SMLF  page 363 : 1 = P0V9_CPU0_RT_2D ; 2 = GND
PC544_3  Q_CAP  0.1UF 25V 10% X7R  pkg 0402  page 195 : 1 = PVDDCR_CPU0_P0_VCCS ; 2 = GND
PC545_4  Q_CAP  0.1UF 25V 10% X7R  pkg 0402  page 195 : 1 = PVDDCR_CPU0_P0_VCCS ; 2 = GND
PC546  Q_CAP  2.2UF 10V 10% X6S  pkg C0402  page 195 : 1 = PVDDCR_CPU0_P0_VCC3 ; 2 = GND
PC547  Q_CAP  2.2UF 10V 10% X6S  pkg C0402  page 195 : 1 = PVDDCR_CPU0_P0_VCC4 ; 2 = GND
PC548_C0P0_3  Q_CAP  2.2UF 10V 10% X6S  pkg C0402  page 195 : 1 = PVDDCR_CPU0_P0_PVCC ; 2 = GND
PC549_C0P0_4  Q_CAP  2.2UF 10V 10% X6S  pkg C0402  page 195 : 1 = PVDDCR_CPU0_P0_PVCC ; 2 = GND
PC550_3  Q_CAP  1UF 25V 10% X6S  pkg C0402  page 195 : 1 = SW_P12V_AUX_PVDDCR_CPU0_P0_FLT ; 2 = GND
PC551_4  Q_CAP  0.1UF 25V 10% X7R  pkg 0402  page 195 : 1 = SW_P12V_AUX_PVDDCR_CPU0_P0_FLT ; 2 = GND
PC552_3  Q_CAP  0.1UF 25V 10% X7R  pkg 0402  page 195 : 1 = SW_P12V_AUX_PVDDCR_CPU0_P0_FLT ; 2 = GND
PC553_4  Q_CAP  1UF 25V 10% X6S  pkg C0402  page 195 : 1 = SW_P12V_AUX_PVDDCR_CPU0_P0_FLT ; 2 = GND
PC554_3  Q_CAP  22UF 16V 20% X6S  pkg C0805  page 195 : 1 = SW_P12V_AUX_PVDDCR_CPU0_P0_FLT ; 2 = GND
PC555_4  Q_CAP  22UF 16V 20% X6S  pkg C0805  page 195 : 1 = SW_P12V_AUX_PVDDCR_CPU0_P0_FLT ; 2 = GND
PC556_3  Q_CAP  22UF 16V 20% X6S  pkg C0805  page 195 : 1 = SW_P12V_AUX_PVDDCR_CPU0_P0_FLT ; 2 = GND
PC557_4  Q_CAP  22UF 16V 20% X6S  pkg C0805  page 195 : 1 = SW_P12V_AUX_PVDDCR_CPU0_P0_FLT ; 2 = GND
PC558_3  Q_CAP  22UF 16V 20% X6S  pkg C0805  page 195 : 1 = SW_P12V_AUX_PVDDCR_CPU0_P0_FLT ; 2 = GND
PC559_4  Q_CAP  22UF 16V 20% X6S  pkg C0805  page 195 : 1 = SW_P12V_AUX_PVDDCR_CPU0_P0_FLT ; 2 = GND
